# TIMECARD (Time Appliance Project (Time Card)) — schematic netlist excerpt (pin names and nets, part order shuffled) for the footprints in the layout excerpt that follows; sources: Cadence DE-HDL packaged netlist, KiCad conversion of R4006-B0001-02_R01.brd

C199  CAPACITOR  0.1UF 10V 10%  pkg SMC_0402R_H022  page 10 : \1\ = XP3R3V_FPGA ; \2\ = SG
L33  FERRITEBEAD  120OHM 25%  pkg SMC_0603R_H030  page 14 : \1\ = XP1R8V_FPGA_VCCAUX ; \2\ = XP1R8V_FPGA

(kicad_pcb
	(version 20260206)
	(generator "pcbnew")
	(generator_version "10.0")
	(general
		(thickness 1.6)
		(legacy_teardrops no)
	)
	(paper "A4")
	(title_block
		(title "timecard-production-celestica-r4006 — R4006-B0001-02_R01.brd")
		(comment 1 "Time Appliance Project (Time Card) / footprints 496-497 of 1113")
	)
	(layers
		(0 "F.Cu" signal "TOP")
		(4 "In1.Cu" signal "L02_GND1")
		(6 "In2.Cu" signal "L03_SIG1")
		(8 "In3.Cu" signal "L04_GND2")
		(10 "In4.Cu" signal "L05_VCC1")
		(12 "In5.Cu" signal "L06_VCC2")
		(14 "In6.Cu" signal "L07_GND3")
		(16 "In7.Cu" signal "L08_SIG2")
		(18 "In8.Cu" signal "L09_GND4")
		(2 "B.Cu" signal "BOTTOM")
		(9 "F.Adhes" user "F.Adhesive")
		(11 "B.Adhes" user "B.Adhesive")
		(13 "F.Paste" user "Package Geometry/Pastemask Top")
		(15 "B.Paste" user "Package Geometry/Pastemask Bottom")
		(5 "F.SilkS" user "Ref Des/Silkscreen Top")
		(7 "B.SilkS" user "Ref Des/Silkscreen Bottom")
		(1 "F.Mask" user "Board Geometry/Soldermask Top")
		(3 "B.Mask" user "Board Geometry/Soldermask Bottom")
		(17 "Dwgs.User" user "User.Drawings")
		(19 "Cmts.User" user "User.Comments")
		(21 "Eco1.User" user "User.Eco1")
		(23 "Eco2.User" user "User.Eco2")
		(25 "Edge.Cuts" user "Board Geometry/Outline")
		(27 "Margin" user)
		(31 "F.CrtYd" user "Package Geometry/Place Bound Top")
		(29 "B.CrtYd" user "Package Geometry/Place Bound Bottom")
		(35 "F.Fab" user "Ref Des/Assembly Top")
		(33 "B.Fab" user "Ref Des/Assembly Bottom")
	)
	(footprint ""
		(layer "F.Cu")
		(at 92.837 -56.007 180)
		(property "Reference" "L33"
			(at 1.0795 -1.30937 0)
			(unlocked yes)
			(layer "F.SilkS")
			(effects
				(font
					(size 0.7874 0.5842)
					(thickness 0.1524)
				)
				(justify left)
			)
		)
		(property "Value" "VAL*"
			(at -0.9398 3.70967 180)
			(unlocked yes)
			(layer "F.Fab")
			(hide yes)
			(effects
				(font
					(size 0.7874 0.5842)
					(thickness 0.1524)
				)
				(justify left)
			)
		)
		(property "Tolerance" "TOL*"
			(at -0.9906 5.00507 180)
			(unlocked yes)
			(layer "Cmts.User")
			(hide yes)
			(effects
				(font
					(size 0.7874 0.5842)
					(thickness 0.1524)
				)
				(justify left)
			)
		)
		(property "User Part Number" "PARTNUM*"
			(at -2.54 2.46507 180)
			(unlocked yes)
			(layer "Cmts.User")
			(hide yes)
			(effects
				(font
					(size 0.7874 0.5842)
					(thickness 0.1524)
				)
				(justify left)
			)
		)
		(property "Device Type" "FERRITEBEAD-G191-10100-01,120OA"
			(at -0.9906 1.22047 180)
			(unlocked yes)
			(layer "F.Fab")
			(hide yes)
			(effects
				(font
					(size 0.7874 0.5842)
					(thickness 0.1524)
				)
				(justify left)
			)
		)
		(duplicate_pad_numbers_are_jumpers no)
		(fp_line
			(start 1.3208 0.7112)
			(end -1.3208 0.7112)
			(stroke
				(width 0.1)
				(type default)
			)
			(layer "F.SilkS")
		)
		(fp_line
			(start 1.3208 -0.7112)
			(end 1.3208 0.7112)
			(stroke
				(width 0.1)
				(type default)
			)
			(layer "F.SilkS")
		)
		(fp_line
			(start -1.3208 0.7112)
			(end -1.3208 -0.7112)
			(stroke
				(width 0.1)
				(type default)
			)
			(layer "F.SilkS")
		)
		(fp_line
			(start -1.3208 -0.7112)
			(end 1.3208 -0.7112)
			(stroke
				(width 0.1)
				(type default)
			)
			(layer "F.SilkS")
		)
		(fp_rect
			(start -1.3208 0.7112)
			(end 1.3208 -0.7112)
			(stroke
				(width 0)
				(type default)
			)
			(fill no)
			(layer "F.CrtYd")
		)
		(fp_line
			(start 0.8128 0.4572)
			(end -0.8128 0.4572)
			(stroke
				(width 0.1)
				(type default)
			)
			(layer "F.Fab")
		)
		(fp_line
			(start 0.8128 -0.4572)
			(end 0.8128 0.4572)
			(stroke
				(width 0.1)
				(type default)
			)
			(layer "F.Fab")
		)
		(fp_line
			(start -0.8128 0.4572)
			(end -0.8128 -0.4572)
			(stroke
				(width 0.1)
				(type default)
			)
			(layer "F.Fab")
		)
		(fp_line
			(start -0.8128 -0.4572)
			(end 0.8128 -0.4572)
			(stroke
				(width 0.1)
				(type default)
			)
			(layer "F.Fab")
		)
		(pad "1" smd rect
			(at -0.6858 0 180)
			(size 0.762 0.8636)
			(layers "F.Cu" "F.Mask" "F.Paste")
			(net "XP1R8V_FPGA_VCCAUX")
		)
		(pad "2" smd rect
			(at 0.6858 0 180)
			(size 0.762 0.8636)
			(layers "F.Cu" "F.Mask" "F.Paste")
			(net "XP1R8V_FPGA")
		)
		(zone
			(layer "F.Cu")
			(hatch none 0.5)
			(connect_pads
				(clearance 0)
			)
			(min_thickness 0.25)
			(keepout
				(tracks not_allowed)
				(vias allowed)
				(pads allowed)
				(copperpour not_allowed)
				(footprints allowed)
			)
			(placement
				(enabled no)
				(sheetname "")
			)
			(fill
				(thermal_gap 0.5)
				(thermal_bridge_width 0.5)
				(island_removal_mode 0)
			)
			(polygon
				(pts
					(xy 92.9894 -56.4642) (xy 92.6846 -56.4642) (xy 92.6846 -55.5498) (xy 92.9894 -55.5498)
				)
			)
		)
		(zone
			(layer "F.Cu")
			(hatch none 0.5)
			(connect_pads
				(clearance 0)
			)
			(min_thickness 0.25)
			(keepout
				(tracks allowed)
				(vias not_allowed)
				(pads allowed)
				(copperpour not_allowed)
				(footprints allowed)
			)
			(placement
				(enabled no)
				(sheetname "")
			)
			(fill
				(thermal_gap 0.5)
				(thermal_bridge_width 0.5)
				(island_removal_mode 0)
			)
			(polygon
				(pts
					(xy 92.9894 -56.4642) (xy 92.6846 -56.4642) (xy 92.6846 -55.5498) (xy 92.9894 -55.5498)
				)
			)
		)
	)
	(footprint ""
		(layer "F.Cu")
		(at 90.9828 -73.0758 90)
		(property "Reference" "C199"
			(at 19.6342 -27.44343 90)
			(unlocked yes)
			(layer "F.SilkS")
			(effects
				(font
					(size 0.7874 0.5842)
					(thickness 0.1524)
				)
			)
		)
		(property "Value" "VAL*"
			(at 0.0762 2.067306 90)
			(unlocked yes)
			(layer "F.Fab")
			(hide yes)
			(effects
				(font
					(size 0.7874 0.5842)
					(thickness 0.1524)
				)
			)
		)
		(property "Device Type" "CAPACITOR-G105-0B104-CK,0.1UF,A"
			(at 0.0508 1.127506 90)
			(unlocked yes)
			(layer "F.Fab")
			(hide yes)
			(effects
				(font
					(size 0.7874 0.5842)
					(thickness 0.1524)
				)
			)
		)
		(property "User Part Number" "PARTNUM*"
			(at 0.1016 4.023106 90)
			(unlocked yes)
			(layer "Cmts.User")
			(hide yes)
			(effects
				(font
					(size 0.7874 0.5842)
					(thickness 0.1524)
				)
			)
		)
		(property "Tolerance" "TOL*"
			(at 0.0762 3.032506 90)
			(unlocked yes)
			(layer "Cmts.User")
			(hide yes)
			(effects
				(font
					(size 0.7874 0.5842)
					(thickness 0.1524)
				)
			)
		)
		(duplicate_pad_numbers_are_jumpers no)
		(fp_line
			(start 1.143 -0.5588)
			(end -1.143 -0.5588)
			(stroke
				(width 0.1)
				(type default)
			)
			(layer "F.SilkS")
		)
		(fp_line
			(start -1.143 -0.5588)
			(end -1.143 0.5588)
			(stroke
				(width 0.1)
				(type default)
			)
			(layer "F.SilkS")
		)
		(fp_line
			(start 1.143 0.5588)
			(end 1.143 -0.5588)
			(stroke
				(width 0.1)
				(type default)
			)
			(layer "F.SilkS")
		)
		(fp_line
			(start -1.143 0.5588)
			(end 1.143 0.5588)
			(stroke
				(width 0.1)
				(type default)
			)
			(layer "F.SilkS")
		)
		(fp_rect
			(start -1.143 -0.5588)
			(end 1.143 0.5588)
			(stroke
				(width 0)
				(type default)
			)
			(fill no)
			(layer "F.CrtYd")
		)
		(fp_line
			(start 0.508 -0.3048)
			(end -0.508 -0.3048)
			(stroke
				(width 0.1)
				(type default)
			)
			(layer "F.Fab")
		)
		(fp_line
			(start -0.508 -0.3048)
			(end -0.508 0.3048)
			(stroke
				(width 0.1)
				(type default)
			)
			(layer "F.Fab")
		)
		(fp_line
			(start 0.508 0.3048)
			(end 0.508 -0.3048)
			(stroke
				(width 0.1)
				(type default)
			)
			(layer "F.Fab")
		)
		(fp_line
			(start -0.508 0.3048)
			(end 0.508 0.3048)
			(stroke
				(width 0.1)
				(type default)
			)
			(layer "F.Fab")
		)
		(pad "1" smd rect
			(at -0.5334 0 90)
			(size 0.7112 0.6096)
			(layers "F.Cu" "F.Mask" "F.Paste")
			(net "XP3R3V_FPGA")
		)
		(pad "2" smd rect
			(at 0.5334 0 90)
			(size 0.7112 0.6096)
			(layers "F.Cu" "F.Mask" "F.Paste")
			(net "SG")
		)
		(zone
			(layer "F.Cu")
			(hatch none 0.5)
			(connect_pads
				(clearance 0)
			)
			(min_thickness 0.25)
			(keepout
				(tracks allowed)
				(vias not_allowed)
				(pads allowed)
				(copperpour not_allowed)
				(footprints allowed)
			)
			(placement
				(enabled no)
				(sheetname "")
			)
			(fill
				(thermal_gap 0.5)
				(thermal_bridge_width 0.5)
				(island_removal_mode 0)
			)
			(polygon
				(pts
					(xy 90.678 -72.9996) (xy 91.2876 -72.9996) (xy 91.2876 -73.152) (xy 90.678 -73.152)
				)
			)
		)
	)
)
